G04 ================== begin FILE IDENTIFICATION RECORD ==================*
G04 Layout Name:  15968-1a.brd*
G04 Film Name:    BMASK*
G04 File Format:  Gerber RS274X*
G04 File Origin:  Cadence Allegro 16.5-S058*
G04 Origin Date:  Fri Oct 14 10:23:22 2016*
G04 *
G04 Layer:  VIA CLASS/SOLDERMASK_BOTTOM*
G04 Layer:  PIN/SOLDERMASK_BOTTOM*
G04 Layer:  PACKAGE GEOMETRY/SOLDERMASK_BOTTOM*
G04 Layer:  DRAWING FORMAT/LAYER_PCB_STORY*
G04 Layer:  DRAWING FORMAT/LAYER_SOLDER_B*
G04 Layer:  BOARD GEOMETRY/SOLDERMASK_BOTTOM*
G04 *
G04 Offset:    (0.00 0.00)*
G04 Mirror:    No*
G04 Mode:      Positive*
G04 Rotation:  0*
G04 FullContactRelief:  No*
G04 UndefLineWidth:     6.00*
G04 ================== end FILE IDENTIFICATION RECORD ====================*
%FSLAX35Y35*MOIN*%
%IR0*IPPOS*OFA0.00000B0.00000*MIA0B0*SFA1.00000B1.00000*%
%AMMACRO29*
4,1,40,.011,.007,
.011,-.007,
.010939,-.007695,
.010759,-.008368,
.010464,-.009,
.010064,-.009571,
.009571,-.010064,
.009,-.010464,
.008368,-.010759,
.007695,-.010939,
.007,-.011,
-.007,-.011,
-.007695,-.010939,
-.008368,-.010759,
-.009,-.010464,
-.009571,-.010064,
-.010064,-.009571,
-.010464,-.009,
-.010759,-.008368,
-.010939,-.007695,
-.011,-.007,
-.011,.007,
-.010939,.007695,
-.010759,.008368,
-.010464,.009,
-.010064,.009571,
-.009571,.010064,
-.009,.010464,
-.008368,.010759,
-.007695,.010939,
-.007,.011,
.007,.011,
.007695,.010939,
.008368,.010759,
.009,.010464,
.009571,.010064,
.010064,.009571,
.010464,.009,
.010759,.008368,
.010939,.007695,
.011,.007,
0.0*
%
%ADD29MACRO29*%
%AMMACRO12*
4,1,40,-.017,-.013,
-.017,.013,
-.016939,.013695,
-.016759,.014368,
-.016464,.015,
-.016064,.015571,
-.015571,.016064,
-.015,.016464,
-.014368,.016759,
-.013695,.016939,
-.013,.017,
.013,.017,
.013695,.016939,
.014368,.016759,
.015,.016464,
.015571,.016064,
.016064,.015571,
.016464,.015,
.016759,.014368,
.016939,.013695,
.017,.013,
.017,-.013,
.016939,-.013695,
.016759,-.014368,
.016464,-.015,
.016064,-.015571,
.015571,-.016064,
.015,-.016464,
.014368,-.016759,
.013695,-.016939,
.013,-.017,
-.013,-.017,
-.013695,-.016939,
-.014368,-.016759,
-.015,-.016464,
-.015571,-.016064,
-.016064,-.015571,
-.016464,-.015,
-.016759,-.014368,
-.016939,-.013695,
-.017,-.013,
0.0*
%
%ADD12MACRO12*%
%ADD15R,.022X.11*%
%ADD45R,.022X.102*%
%ADD38R,.05X.008*%
%ADD44C,.042*%
%ADD42C,.08*%
%AMMACRO34*
4,1,32,-.00137,.05008,
.025,.05008,
.025,.06208,
-.025,.06208,
-.025,-.06209,
.025,-.06209,
.025,-.05409,
-.00137,-.05409,
-.00137,-.04635,
.025,-.04635,
.025,-.03835,
-.00137,-.03835,
-.00137,-.0306,
.025,-.0306,
.025,-.0226,
-.00137,-.0226,
-.00137,-.01485,
.025,-.01485,
.025,-.00685,
-.00137,-.00685,
-.00137,.0009,
.025,.0009,
.025,.0089,
-.00137,.0089,
-.00137,.01665,
.025,.01665,
.025,.02465,
-.00137,.02465,
-.00137,.03239,
.025,.03239,
.025,.04039,
-.00137,.04039,
-.00137,.05008,
0.0*
%
%ADD34MACRO34*%
%ADD13C,.028*%
%ADD43C,.093*%
%ADD10C,.086*%
%AMMACRO26*
4,1,40,.007,-.011,
-.007,-.011,
-.007695,-.010939,
-.008368,-.010759,
-.009,-.010464,
-.009571,-.010064,
-.010064,-.009571,
-.010464,-.009,
-.010759,-.008368,
-.010939,-.007695,
-.011,-.007,
-.011,.007,
-.010939,.007695,
-.010759,.008368,
-.010464,.009,
-.010064,.009571,
-.009571,.010064,
-.009,.010464,
-.008368,.010759,
-.007695,.010939,
-.007,.011,
.007,.011,
.007695,.010939,
.008368,.010759,
.009,.010464,
.009571,.010064,
.010064,.009571,
.010464,.009,
.010759,.008368,
.010939,.007695,
.011,.007,
.011,-.007,
.010939,-.007695,
.010759,-.008368,
.010464,-.009,
.010064,-.009571,
.009571,-.010064,
.009,-.010464,
.008368,-.010759,
.007695,-.010939,
.007,-.011,
0.0*
%
%ADD26MACRO26*%
%AMMACRO21*
4,1,40,-.008,.012,
.008,.012,
.008695,.011939,
.009368,.011759,
.01,.011464,
.010571,.011064,
.011064,.010571,
.011464,.01,
.011759,.009368,
.011939,.008695,
.012,.008,
.012,-.008,
.011939,-.008695,
.011759,-.009368,
.011464,-.01,
.011064,-.010571,
.010571,-.011064,
.01,-.011464,
.009368,-.011759,
.008695,-.011939,
.008,-.012,
-.008,-.012,
-.008695,-.011939,
-.009368,-.011759,
-.01,-.011464,
-.010571,-.011064,
-.011064,-.010571,
-.011464,-.01,
-.011759,-.009368,
-.011939,-.008695,
-.012,-.008,
-.012,.008,
-.011939,.008695,
-.011759,.009368,
-.011464,.01,
-.011064,.010571,
-.010571,.011064,
-.01,.011464,
-.009368,.011759,
-.008695,.011939,
-.008,.012,
0.0*
%
%ADD21MACRO21*%
%AMMACRO32*
4,1,40,-.013,.017,
.013,.017,
.013695,.016939,
.014368,.016759,
.015,.016464,
.015571,.016064,
.016064,.015571,
.016464,.015,
.016759,.014368,
.016939,.013695,
.017,.013,
.017,-.013,
.016939,-.013695,
.016759,-.014368,
.016464,-.015,
.016064,-.015571,
.015571,-.016064,
.015,-.016464,
.014368,-.016759,
.013695,-.016939,
.013,-.017,
-.013,-.017,
-.013695,-.016939,
-.014368,-.016759,
-.015,-.016464,
-.015571,-.016064,
-.016064,-.015571,
-.016464,-.015,
-.016759,-.014368,
-.016939,-.013695,
-.017,-.013,
-.017,.013,
-.016939,.013695,
-.016759,.014368,
-.016464,.015,
-.016064,.015571,
-.015571,.016064,
-.015,.016464,
-.014368,.016759,
-.013695,.016939,
-.013,.017,
0.0*
%
%ADD32MACRO32*%
%AMMACRO40*
4,1,6,.025,-.0135,
.005,.0065,
.005,.0135,
-.005,.0135,
-.005,.0065,
-.025,-.0135,
.025,-.0135,
0.0*
%
%ADD40MACRO40*%
%AMMACRO17*
4,1,40,.017,.013,
.017,-.013,
.016939,-.013695,
.016759,-.014368,
.016464,-.015,
.016064,-.015571,
.015571,-.016064,
.015,-.016464,
.014368,-.016759,
.013695,-.016939,
.013,-.017,
-.013,-.017,
-.013695,-.016939,
-.014368,-.016759,
-.015,-.016464,
-.015571,-.016064,
-.016064,-.015571,
-.016464,-.015,
-.016759,-.014368,
-.016939,-.013695,
-.017,-.013,
-.017,.013,
-.016939,.013695,
-.016759,.014368,
-.016464,.015,
-.016064,.015571,
-.015571,.016064,
-.015,.016464,
-.014368,.016759,
-.013695,.016939,
-.013,.017,
.013,.017,
.013695,.016939,
.014368,.016759,
.015,.016464,
.015571,.016064,
.016064,.015571,
.016464,.015,
.016759,.014368,
.016939,.013695,
.017,.013,
0.0*
%
%ADD17MACRO17*%
%AMMACRO27*
4,1,40,.007,-.011,
-.007,-.011,
-.007695,-.010939,
-.008368,-.010759,
-.009,-.010464,
-.009571,-.010064,
-.010064,-.009571,
-.010464,-.009,
-.010759,-.008368,
-.010939,-.007695,
-.011,-.007,
-.011,.007,
-.010939,.007695,
-.010759,.008368,
-.010464,.009,
-.010064,.009571,
-.009571,.010064,
-.009,.010464,
-.008368,.010759,
-.007695,.010939,
-.007,.011,
.007,.011,
.007695,.010939,
.008368,.010759,
.009,.010464,
.009571,.010064,
.010064,.009571,
.010464,.009,
.010759,.008368,
.010939,.007695,
.011,.007,
.011,-.007,
.010939,-.007695,
.010759,-.008368,
.010464,-.009,
.010064,-.009571,
.009571,-.010064,
.009,-.010464,
.008368,-.010759,
.007695,-.010939,
.007,-.011,
0.0*
%
%ADD27MACRO27*%
%AMMACRO20*
4,1,40,-.008,.012,
.008,.012,
.008695,.011939,
.009368,.011759,
.01,.011464,
.010571,.011064,
.011064,.010571,
.011464,.01,
.011759,.009368,
.011939,.008695,
.012,.008,
.012,-.008,
.011939,-.008695,
.011759,-.009368,
.011464,-.01,
.011064,-.010571,
.010571,-.011064,
.01,-.011464,
.009368,-.011759,
.008695,-.011939,
.008,-.012,
-.008,-.012,
-.008695,-.011939,
-.009368,-.011759,
-.01,-.011464,
-.010571,-.011064,
-.011064,-.010571,
-.011464,-.01,
-.011759,-.009368,
-.011939,-.008695,
-.012,-.008,
-.012,.008,
-.011939,.008695,
-.011759,.009368,
-.011464,.01,
-.011064,.010571,
-.010571,.011064,
-.01,.011464,
-.009368,.011759,
-.008695,.011939,
-.008,.012,
0.0*
%
%ADD20MACRO20*%
%AMMACRO33*
4,1,40,-.013,.017,
.013,.017,
.013695,.016939,
.014368,.016759,
.015,.016464,
.015571,.016064,
.016064,.015571,
.016464,.015,
.016759,.014368,
.016939,.013695,
.017,.013,
.017,-.013,
.016939,-.013695,
.016759,-.014368,
.016464,-.015,
.016064,-.015571,
.015571,-.016064,
.015,-.016464,
.014368,-.016759,
.013695,-.016939,
.013,-.017,
-.013,-.017,
-.013695,-.016939,
-.014368,-.016759,
-.015,-.016464,
-.015571,-.016064,
-.016064,-.015571,
-.016464,-.015,
-.016759,-.014368,
-.016939,-.013695,
-.017,-.013,
-.017,.013,
-.016939,.013695,
-.016759,.014368,
-.016464,.015,
-.016064,.015571,
-.015571,.016064,
-.015,.016464,
-.014368,.016759,
-.013695,.016939,
-.013,.017,
0.0*
%
%ADD33MACRO33*%
%AMMACRO18*
4,1,40,.017,.013,
.017,-.013,
.016939,-.013695,
.016759,-.014368,
.016464,-.015,
.016064,-.015571,
.015571,-.016064,
.015,-.016464,
.014368,-.016759,
.013695,-.016939,
.013,-.017,
-.013,-.017,
-.013695,-.016939,
-.014368,-.016759,
-.015,-.016464,
-.015571,-.016064,
-.016064,-.015571,
-.016464,-.015,
-.016759,-.014368,
-.016939,-.013695,
-.017,-.013,
-.017,.013,
-.016939,.013695,
-.016759,.014368,
-.016464,.015,
-.016064,.015571,
-.015571,.016064,
-.015,.016464,
-.014368,.016759,
-.013695,.016939,
-.013,.017,
.013,.017,
.013695,.016939,
.014368,.016759,
.015,.016464,
.015571,.016064,
.016064,.015571,
.016464,.015,
.016759,.014368,
.016939,.013695,
.017,.013,
0.0*
%
%ADD18MACRO18*%
%ADD37R,.05X.012*%
%ADD36R,.052X.012*%
%ADD46C,.101*%
%ADD16R,.128X.107*%
%ADD19R,.045X.055*%
%ADD41R,.055X.045*%
%ADD35R,.014X.089*%
%ADD14C,.374*%
%AMMACRO30*
4,1,40,-.007,.011,
.007,.011,
.007695,.010939,
.008368,.010759,
.009,.010464,
.009571,.010064,
.010064,.009571,
.010464,.009,
.010759,.008368,
.010939,.007695,
.011,.007,
.011,-.007,
.010939,-.007695,
.010759,-.008368,
.010464,-.009,
.010064,-.009571,
.009571,-.010064,
.009,-.010464,
.008368,-.010759,
.007695,-.010939,
.007,-.011,
-.007,-.011,
-.007695,-.010939,
-.008368,-.010759,
-.009,-.010464,
-.009571,-.010064,
-.010064,-.009571,
-.010464,-.009,
-.010759,-.008368,
-.010939,-.007695,
-.011,-.007,
-.011,.007,
-.010939,.007695,
-.010759,.008368,
-.010464,.009,
-.010064,.009571,
-.009571,.010064,
-.009,.010464,
-.008368,.010759,
-.007695,.010939,
-.007,.011,
0.0*
%
%ADD30MACRO30*%
%AMMACRO25*
4,1,40,.008,-.012,
-.008,-.012,
-.008695,-.011939,
-.009368,-.011759,
-.01,-.011464,
-.010571,-.011064,
-.011064,-.010571,
-.011464,-.01,
-.011759,-.009368,
-.011939,-.008695,
-.012,-.008,
-.012,.008,
-.011939,.008695,
-.011759,.009368,
-.011464,.01,
-.011064,.010571,
-.010571,.011064,
-.01,.011464,
-.009368,.011759,
-.008695,.011939,
-.008,.012,
.008,.012,
.008695,.011939,
.009368,.011759,
.01,.011464,
.010571,.011064,
.011064,.010571,
.011464,.01,
.011759,.009368,
.011939,.008695,
.012,.008,
.012,-.008,
.011939,-.008695,
.011759,-.009368,
.011464,-.01,
.011064,-.010571,
.010571,-.011064,
.01,-.011464,
.009368,-.011759,
.008695,-.011939,
.008,-.012,
0.0*
%
%ADD25MACRO25*%
%AMMACRO23*
4,1,40,.012,.008,
.012,-.008,
.011939,-.008695,
.011759,-.009368,
.011464,-.01,
.011064,-.010571,
.010571,-.011064,
.01,-.011464,
.009368,-.011759,
.008695,-.011939,
.008,-.012,
-.008,-.012,
-.008695,-.011939,
-.009368,-.011759,
-.01,-.011464,
-.010571,-.011064,
-.011064,-.010571,
-.011464,-.01,
-.011759,-.009368,
-.011939,-.008695,
-.012,-.008,
-.012,.008,
-.011939,.008695,
-.011759,.009368,
-.011464,.01,
-.011064,.010571,
-.010571,.011064,
-.01,.011464,
-.009368,.011759,
-.008695,.011939,
-.008,.012,
.008,.012,
.008695,.011939,
.009368,.011759,
.01,.011464,
.010571,.011064,
.011064,.010571,
.011464,.01,
.011759,.009368,
.011939,.008695,
.012,.008,
0.0*
%
%ADD23MACRO23*%
%AMMACRO28*
4,1,40,.011,.007,
.011,-.007,
.010939,-.007695,
.010759,-.008368,
.010464,-.009,
.010064,-.009571,
.009571,-.010064,
.009,-.010464,
.008368,-.010759,
.007695,-.010939,
.007,-.011,
-.007,-.011,
-.007695,-.010939,
-.008368,-.010759,
-.009,-.010464,
-.009571,-.010064,
-.010064,-.009571,
-.010464,-.009,
-.010759,-.008368,
-.010939,-.007695,
-.011,-.007,
-.011,.007,
-.010939,.007695,
-.010759,.008368,
-.010464,.009,
-.010064,.009571,
-.009571,.010064,
-.009,.010464,
-.008368,.010759,
-.007695,.010939,
-.007,.011,
.007,.011,
.007695,.010939,
.008368,.010759,
.009,.010464,
.009571,.010064,
.010064,.009571,
.010464,.009,
.010759,.008368,
.010939,.007695,
.011,.007,
0.0*
%
%ADD28MACRO28*%
%AMMACRO11*
4,1,40,-.017,-.013,
-.017,.013,
-.016939,.013695,
-.016759,.014368,
-.016464,.015,
-.016064,.015571,
-.015571,.016064,
-.015,.016464,
-.014368,.016759,
-.013695,.016939,
-.013,.017,
.013,.017,
.013695,.016939,
.014368,.016759,
.015,.016464,
.015571,.016064,
.016064,.015571,
.016464,.015,
.016759,.014368,
.016939,.013695,
.017,.013,
.017,-.013,
.016939,-.013695,
.016759,-.014368,
.016464,-.015,
.016064,-.015571,
.015571,-.016064,
.015,-.016464,
.014368,-.016759,
.013695,-.016939,
.013,-.017,
-.013,-.017,
-.013695,-.016939,
-.014368,-.016759,
-.015,-.016464,
-.015571,-.016064,
-.016064,-.015571,
-.016464,-.015,
-.016759,-.014368,
-.016939,-.013695,
-.017,-.013,
0.0*
%
%ADD11MACRO11*%
%AMMACRO39*
4,1,6,.005,-.0135,
.005,-.0065,
.025,.0135,
-.025,.0135,
-.005,-.0065,
-.005,-.0135,
.005,-.0135,
0.0*
%
%ADD39MACRO39*%
%AMMACRO31*
4,1,40,-.007,.011,
.007,.011,
.007695,.010939,
.008368,.010759,
.009,.010464,
.009571,.010064,
.010064,.009571,
.010464,.009,
.010759,.008368,
.010939,.007695,
.011,.007,
.011,-.007,
.010939,-.007695,
.010759,-.008368,
.010464,-.009,
.010064,-.009571,
.009571,-.010064,
.009,-.010464,
.008368,-.010759,
.007695,-.010939,
.007,-.011,
-.007,-.011,
-.007695,-.010939,
-.008368,-.010759,
-.009,-.010464,
-.009571,-.010064,
-.010064,-.009571,
-.010464,-.009,
-.010759,-.008368,
-.010939,-.007695,
-.011,-.007,
-.011,.007,
-.010939,.007695,
-.010759,.008368,
-.010464,.009,
-.010064,.009571,
-.009571,.010064,
-.009,.010464,
-.008368,.010759,
-.007695,.010939,
-.007,.011,
0.0*
%
%ADD31MACRO31*%
%AMMACRO24*
4,1,40,.008,-.012,
-.008,-.012,
-.008695,-.011939,
-.009368,-.011759,
-.01,-.011464,
-.010571,-.011064,
-.011064,-.010571,
-.011464,-.01,
-.011759,-.009368,
-.011939,-.008695,
-.012,-.008,
-.012,.008,
-.011939,.008695,
-.011759,.009368,
-.011464,.01,
-.011064,.010571,
-.010571,.011064,
-.01,.011464,
-.009368,.011759,
-.008695,.011939,
-.008,.012,
.008,.012,
.008695,.011939,
.009368,.011759,
.01,.011464,
.010571,.011064,
.011064,.010571,
.011464,.01,
.011759,.009368,
.011939,.008695,
.012,.008,
.012,-.008,
.011939,-.008695,
.011759,-.009368,
.011464,-.01,
.011064,-.010571,
.010571,-.011064,
.01,-.011464,
.009368,-.011759,
.008695,-.011939,
.008,-.012,
0.0*
%
%ADD24MACRO24*%
%AMMACRO22*
4,1,40,.012,.008,
.012,-.008,
.011939,-.008695,
.011759,-.009368,
.011464,-.01,
.011064,-.010571,
.010571,-.011064,
.01,-.011464,
.009368,-.011759,
.008695,-.011939,
.008,-.012,
-.008,-.012,
-.008695,-.011939,
-.009368,-.011759,
-.01,-.011464,
-.010571,-.011064,
-.011064,-.010571,
-.011464,-.01,
-.011759,-.009368,
-.011939,-.008695,
-.012,-.008,
-.012,.008,
-.011939,.008695,
-.011759,.009368,
-.011464,.01,
-.011064,.010571,
-.010571,.011064,
-.01,.011464,
-.009368,.011759,
-.008695,.011939,
-.008,.012,
.008,.012,
.008695,.011939,
.009368,.011759,
.01,.011464,
.010571,.011064,
.011064,.010571,
.011464,.01,
.011759,.009368,
.011939,.008695,
.012,.008,
0.0*
%
%ADD22MACRO22*%
%ADD47C,.02*%
%ADD48C,.006*%
G75*
%LPD*%
G75*
G36*
G01X72653Y-73646D02*
X405733D01*
Y-58409D01*
X72653D01*
Y-73646D01*
G37*
G36*
G01X440369D02*
X540379D01*
Y-59209D01*
X440369D01*
Y-73646D01*
G37*
G54D10*
X21800Y-41500D03*
X14794Y226306D03*
X542107Y17432D03*
X585785Y228866D03*
X610300Y-43600D03*
X612500Y540800D03*
G54D11*
X24400Y65400D03*
X70800Y65700D03*
G54D20*
X32300Y74900D03*
G54D30*
X43000Y80700D03*
G54D21*
X32300Y71300D03*
G54D12*
X24400Y59800D03*
X70800Y60100D03*
G54D22*
X34700Y82900D03*
X52567Y56182D03*
G54D31*
X39600Y80700D03*
G54D40*
X30900Y60050D03*
G54D13*
X28000Y69800D03*
X26400Y42900D03*
X27800Y75300D03*
X84100Y-19500D03*
X106900Y15700D03*
X102700Y2000D03*
X98200Y6200D03*
X91363Y12538D03*
X76600Y85700D03*
X93200Y69100D03*
X90300Y59600D03*
X45946Y93127D03*
X39700Y66400D03*
X51600Y89900D03*
X55300Y86600D03*
X44500Y64500D03*
X79600Y63900D03*
X36847Y157992D03*
X55500Y168400D03*
X95800Y175700D03*
X105400Y168500D03*
X71500Y172300D03*
X43400Y191700D03*
X83500Y192900D03*
X96000Y195800D03*
X156600Y4900D03*
X126517Y-4483D03*
X109300Y-28000D03*
X125000Y36300D03*
X173600Y39200D03*
X161400Y62500D03*
X154300Y60200D03*
X120200Y78900D03*
X113600Y90100D03*
X108200Y100300D03*
X118800Y94600D03*
X173800Y171200D03*
X113600Y164600D03*
X168800Y169600D03*
X153700Y182800D03*
X184500Y184800D03*
X183900Y189900D03*
X181600Y194800D03*
X187400Y195900D03*
X169200Y188000D03*
X238400Y89300D03*
X221400Y179200D03*
X203700Y194000D03*
X260700Y197900D03*
X246200Y193600D03*
X209800Y183700D03*
X342100Y179200D03*
X274479Y167895D03*
X293300Y188200D03*
X426600Y-20400D03*
X427800Y74900D03*
X351300Y82000D03*
X353900Y29900D03*
X350500Y46600D03*
X426500Y26900D03*
X417700Y27800D03*
X507600Y204400D03*
X523000Y68700D03*
X524200Y167800D03*
X517900Y157400D03*
X555300Y172700D03*
X544200Y169500D03*
X515800Y219500D03*
X589800Y200900D03*
G54D23*
X31100Y82900D03*
X48967Y56182D03*
G54D14*
X15748Y128150D03*
X542913D03*
G54D41*
X85100Y30700D03*
Y23100D03*
Y41900D03*
Y49500D03*
X77400Y41900D03*
Y49500D03*
Y30700D03*
Y23100D03*
G54D32*
X44800Y85200D03*
G54D24*
X36500Y71300D03*
G54D33*
X39200Y85200D03*
G54D42*
X40794Y230682D03*
X37095Y524125D03*
X540347Y32747D03*
X572386Y532294D03*
X594107Y-26510D03*
X599868Y229462D03*
G54D15*
X105355Y-63909D03*
X102205D03*
X99055D03*
X95906D03*
X92756D03*
X89607D03*
X86457D03*
X83307D03*
X80158D03*
X77008D03*
X174646D03*
X171496D03*
X168347D03*
X165197D03*
X162048D03*
X158898D03*
X155748D03*
X152599D03*
X149449D03*
X146300D03*
X143150D03*
X140000D03*
X136851D03*
X133701D03*
X130551D03*
X127402D03*
X124252D03*
X121103D03*
X117953D03*
X114803D03*
X111654D03*
X108504D03*
X265985D03*
X262835D03*
X259685D03*
X256536D03*
X253386D03*
X250237D03*
X247087D03*
X243937D03*
X240788D03*
X237638D03*
X234489D03*
X231339D03*
X228189D03*
X225040D03*
X221890D03*
X218740D03*
X215591D03*
X212441D03*
X209292D03*
X206142D03*
X202992D03*
X199843D03*
X196693D03*
X193544D03*
X190394D03*
X347874D03*
X344725D03*
X341575D03*
X338426D03*
X335276D03*
X332126D03*
X328977D03*
X325827D03*
X322677D03*
X319528D03*
X316378D03*
X313229D03*
X310079D03*
X306929D03*
X303780D03*
X300630D03*
X297481D03*
X294331D03*
X291181D03*
X288032D03*
X284882D03*
X281733D03*
X278583D03*
X275433D03*
X272284D03*
X269134D03*
X401418D03*
X398268D03*
X395118D03*
X391969D03*
X388819D03*
X385670D03*
X382520D03*
X379370D03*
X376221D03*
X373071D03*
X369922D03*
X366772D03*
X363622D03*
X360473D03*
X357323D03*
X354174D03*
X351024D03*
G54D25*
X36500Y74900D03*
G54D16*
X58400Y25157D03*
Y47243D03*
G54D43*
X168268Y143189D03*
Y223189D03*
X456258Y143189D03*
Y223189D03*
G54D34*
X62437Y70885D03*
G54D35*
X55819Y75234D03*
Y64366D03*
X58181D03*
G54D17*
X40900Y49500D03*
G54D26*
X31200Y79000D03*
X75300Y60000D03*
X32700Y67300D03*
G54D44*
X122403Y148109D03*
X126338Y155984D03*
X130278Y148109D03*
X134213Y155984D03*
X138148Y148109D03*
X142088Y155984D03*
X146023Y148109D03*
X149963Y155984D03*
X153898Y148109D03*
X157833Y155984D03*
X161773Y148109D03*
X173583Y155984D03*
X177518Y148109D03*
X181458Y155984D03*
X185393Y148109D03*
X189333Y155984D03*
X122403Y138269D03*
X126338Y130394D03*
X130278Y138269D03*
X134213Y130394D03*
X138148Y138269D03*
X142088Y130394D03*
X146023Y138269D03*
X149963Y130394D03*
X153898Y138269D03*
X157833Y130394D03*
X161773Y138269D03*
X173583Y130394D03*
X177518Y138269D03*
X181458Y130394D03*
X185393Y138269D03*
X189333Y130394D03*
X122403Y228109D03*
X126338Y235984D03*
X130278Y228109D03*
X134213Y235984D03*
X138148Y228109D03*
X142088Y235984D03*
X146023Y228109D03*
X149963Y235984D03*
X153898Y228109D03*
X157833Y235984D03*
X161773Y228109D03*
X173583Y235984D03*
X177518Y228109D03*
X181458Y235984D03*
X185393Y228109D03*
X189333Y235984D03*
X122403Y218269D03*
X126338Y210394D03*
X130278Y218269D03*
X134213Y210394D03*
X138148Y218269D03*
X142088Y210394D03*
X146023Y218269D03*
X149963Y210394D03*
X153898Y218269D03*
X157833Y210394D03*
X161773Y218269D03*
X173583Y210394D03*
X177518Y218269D03*
X181458Y210394D03*
X185393Y218269D03*
X189333Y210394D03*
X193268Y148109D03*
X197203Y155984D03*
X201143Y148109D03*
X205078Y155984D03*
X209018Y148109D03*
X212953Y155984D03*
X216888Y148109D03*
X220828Y155984D03*
X224763Y148109D03*
X228703Y155984D03*
X232638Y148109D03*
X236573Y155984D03*
X240513Y148109D03*
X244448Y155984D03*
X248388Y148109D03*
X252323Y155984D03*
X256258Y148109D03*
X260198Y155984D03*
X264133Y148109D03*
X268073Y155984D03*
X193268Y138269D03*
X197203Y130394D03*
X201143Y138269D03*
X205078Y130394D03*
X209018Y138269D03*
X212953Y130394D03*
X216888Y138269D03*
X220828Y130394D03*
X224763Y138269D03*
X228703Y130394D03*
X232638Y138269D03*
X236573Y130394D03*
X240513Y138269D03*
X244448Y130394D03*
X248388Y138269D03*
X252323Y130394D03*
X256258Y138269D03*
X260198Y130394D03*
X264133Y138269D03*
X268073Y130394D03*
X193268Y228109D03*
X197203Y235984D03*
X201143Y228109D03*
X205078Y235984D03*
X209018Y228109D03*
X212953Y235984D03*
X216888Y228109D03*
X220828Y235984D03*
X224763Y228109D03*
X228703Y235984D03*
X232638Y228109D03*
X236573Y235984D03*
X240513Y228109D03*
X244448Y235984D03*
X248388Y228109D03*
X252323Y235984D03*
X256258Y228109D03*
X260198Y235984D03*
X264133Y228109D03*
X268073Y235984D03*
X193268Y218269D03*
X197203Y210394D03*
X201143Y218269D03*
X205078Y210394D03*
X209018Y218269D03*
X212953Y210394D03*
X216888Y218269D03*
X220828Y210394D03*
X224763Y218269D03*
X228703Y210394D03*
X232638Y218269D03*
X236573Y210394D03*
X240513Y218269D03*
X244448Y210394D03*
X248388Y218269D03*
X252323Y210394D03*
X256258Y218269D03*
X260198Y210394D03*
X264133Y218269D03*
X268073Y210394D03*
X272008Y148109D03*
X275943Y155984D03*
X279883Y148109D03*
X283818Y155984D03*
X287758Y148109D03*
X291693Y155984D03*
X295628Y148109D03*
X299568Y155984D03*
X303503Y148109D03*
X307443Y155984D03*
X311378Y148109D03*
X315313Y155984D03*
X319253Y148109D03*
X323188Y155984D03*
X327128Y148109D03*
X331063Y155984D03*
X334998Y148109D03*
X338938Y155984D03*
X342873Y148109D03*
X346813Y155984D03*
X272008Y138269D03*
X275943Y130394D03*
X279883Y138269D03*
X283818Y130394D03*
X287758Y138269D03*
X291693Y130394D03*
X295628Y138269D03*
X299568Y130394D03*
X303503Y138269D03*
X307443Y130394D03*
X311378Y138269D03*
X315313Y130394D03*
X319253Y138269D03*
X323188Y130394D03*
X327128Y138269D03*
X331063Y130394D03*
X334998Y138269D03*
X338938Y130394D03*
X342873Y138269D03*
X346813Y130394D03*
X272008Y228109D03*
X275943Y235984D03*
X279883Y228109D03*
X283818Y235984D03*
X287758Y228109D03*
X291693Y235984D03*
X295628Y228109D03*
X299568Y235984D03*
X303503Y228109D03*
X307443Y235984D03*
X311378Y228109D03*
X315313Y235984D03*
X319253Y228109D03*
X323188Y235984D03*
X327128Y228109D03*
X331063Y235984D03*
X334998Y228109D03*
X338938Y235984D03*
X342873Y228109D03*
X346813Y235984D03*
X272008Y218269D03*
X275943Y210394D03*
X279883Y218269D03*
X283818Y210394D03*
X287758Y218269D03*
X291693Y210394D03*
X295628Y218269D03*
X299568Y210394D03*
X303503Y218269D03*
X307443Y210394D03*
X311378Y218269D03*
X315313Y210394D03*
X319253Y218269D03*
X323188Y210394D03*
X327128Y218269D03*
X331063Y210394D03*
X334998Y218269D03*
X338938Y210394D03*
X342873Y218269D03*
X346813Y210394D03*
X350748Y148109D03*
X354683Y155984D03*
X358623Y148109D03*
X362558Y155984D03*
X366498Y148109D03*
X370433Y155984D03*
X374368Y148109D03*
X378308Y155984D03*
X382243Y148109D03*
X386183Y155984D03*
X390118Y148109D03*
X394053Y155984D03*
X397993Y148109D03*
X401928Y155984D03*
X405868Y148109D03*
X409803Y155984D03*
X413738Y148109D03*
X417678Y155984D03*
X421613Y148109D03*
X425553Y155984D03*
X429488Y148109D03*
X350748Y138269D03*
X354683Y130394D03*
X358623Y138269D03*
X362558Y130394D03*
X366498Y138269D03*
X370433Y130394D03*
X374368Y138269D03*
X378308Y130394D03*
X382243Y138269D03*
X386183Y130394D03*
X390118Y138269D03*
X394053Y130394D03*
X397993Y138269D03*
X401928Y130394D03*
X405868Y138269D03*
X409803Y130394D03*
X413738Y138269D03*
X417678Y130394D03*
X421613Y138269D03*
X425553Y130394D03*
X429488Y138269D03*
X350748Y228109D03*
X354683Y235984D03*
X358623Y228109D03*
X362558Y235984D03*
X366498Y228109D03*
X370433Y235984D03*
X374368Y228109D03*
X378308Y235984D03*
X382243Y228109D03*
X386183Y235984D03*
X390118Y228109D03*
X394053Y235984D03*
X397993Y228109D03*
X401928Y235984D03*
X405868Y228109D03*
X409803Y235984D03*
X413738Y228109D03*
X417678Y235984D03*
X421613Y228109D03*
X425553Y235984D03*
X429488Y228109D03*
X350748Y218269D03*
X354683Y210394D03*
X358623Y218269D03*
X362558Y210394D03*
X366498Y218269D03*
X370433Y210394D03*
X374368Y218269D03*
X378308Y210394D03*
X382243Y218269D03*
X386183Y210394D03*
X390118Y218269D03*
X394053Y210394D03*
X397993Y218269D03*
X401928Y210394D03*
X405868Y218269D03*
X409803Y210394D03*
X413738Y218269D03*
X417678Y210394D03*
X421613Y218269D03*
X425553Y210394D03*
X429488Y218269D03*
X433423Y155984D03*
X437363Y148109D03*
X441298Y155984D03*
X445238Y148109D03*
X449173Y155984D03*
X433423Y130394D03*
X437363Y138269D03*
X441298Y130394D03*
X445238Y138269D03*
X449173Y130394D03*
X433423Y235984D03*
X437363Y228109D03*
X441298Y235984D03*
X445238Y228109D03*
X449173Y235984D03*
X433423Y210394D03*
X437363Y218269D03*
X441298Y210394D03*
X445238Y218269D03*
X449173Y210394D03*
G54D36*
X51663Y63107D03*
G54D18*
X40900Y55100D03*
G54D27*
X34600Y79000D03*
X78700Y60000D03*
X36100Y67300D03*
G54D45*
X444705Y-64309D03*
X447854D03*
X451004D03*
X454154D03*
X457303D03*
X460453D03*
X463602D03*
X466752D03*
X469902D03*
X473051D03*
X476201D03*
X479350D03*
X482500D03*
X485650D03*
X488799D03*
X491949D03*
X495098D03*
X498248D03*
X501398D03*
X504547D03*
X507697D03*
X510846D03*
X513996D03*
X517146D03*
X520295D03*
X523445D03*
X526594D03*
X529744D03*
X532894D03*
X536043D03*
G54D28*
X36800Y59800D03*
X44500Y70800D03*
X42100Y91000D03*
G54D19*
X62700Y85600D03*
X70300D03*
G54D46*
X539370Y190256D03*
Y206792D03*
X561024Y190256D03*
Y206792D03*
G54D37*
X51563Y76493D03*
X62437Y63107D03*
G54D47*
G01X-84798Y-164972D02*
Y-244972D01*
G01D02*
X1172402D01*
G01X-88798Y-148972D02*
G02I-12000J0D01*
G01X-93948D02*
G02I-6850J0D01*
G01X-100798Y-164972D02*
Y-132972D01*
G01X-84798Y-148972D02*
X-116798D01*
G01X-84798Y-164972D02*
X1172402D01*
G01X-84798Y-200472D02*
X1172402D01*
G01X384902Y-164972D02*
Y-244972D01*
G01X522402Y-164972D02*
Y-244972D01*
G01X637402Y-164972D02*
Y-244972D01*
G01X804902Y-164972D02*
Y-244972D01*
G01X974902Y-164972D02*
Y-244972D01*
G01X1172402Y-164972D02*
Y-244972D01*
G01X1200402Y-148972D02*
G02I-12000J0D01*
G01X1195252D02*
G02I-6850J0D01*
G01X1188402Y-164972D02*
Y-132972D01*
G01X1204402Y-148972D02*
X1172402D01*
G54D38*
X51563Y74524D03*
Y72950D03*
Y71375D03*
Y69800D03*
Y68225D03*
Y66650D03*
Y65076D03*
G54D29*
X36800Y63200D03*
X44500Y74200D03*
X42100Y94400D03*
G54D48*
G01X-65001Y-234972D02*
Y-217472D01*
X-60635D01*
X-58888Y-218347D01*
X-57578Y-219514D01*
X-56486Y-221263D01*
X-55613Y-223306D01*
X-55395Y-226222D01*
X-55613Y-229139D01*
X-56486Y-231181D01*
X-57578Y-232931D01*
X-58888Y-234097D01*
X-60635Y-234972D01*
X-65001D01*
G01X-48157Y-217472D02*
X-42698Y-234972D01*
X-37239Y-217472D01*
G01X-25198D02*
Y-234972D01*
G01X-30220Y-217472D02*
X-20176D01*
G01X5435Y-234972D02*
Y-217472D01*
X10894D01*
X12640Y-218347D01*
X13732Y-219514D01*
X14169Y-221847D01*
X13732Y-224181D01*
X12422Y-225639D01*
X10894Y-226514D01*
X5435D01*
G01X10894D02*
X14169Y-234972D01*
G01X27302Y-223306D02*
Y-234972D01*
G01Y-218639D02*
X26865Y-218347D01*
Y-217764D01*
X27302Y-217472D01*
X27739Y-217764D01*
Y-218347D01*
X27302Y-218639D01*
G01X41527Y-232931D02*
X42619Y-234097D01*
X44147Y-234972D01*
X45457D01*
X46767Y-234389D01*
X47640Y-233514D01*
X48077Y-232348D01*
X47859Y-230597D01*
X46985Y-229722D01*
X43055Y-227972D01*
X42182Y-225930D01*
X42619Y-224472D01*
X43492Y-223597D01*
X44802Y-223306D01*
X46112Y-223597D01*
X47422Y-224472D01*
G01X59027Y-227097D02*
X66014D01*
X65359Y-225055D01*
X64267Y-223889D01*
X62739Y-223306D01*
X61210Y-223597D01*
X59900Y-224472D01*
X59027Y-226514D01*
X58590Y-228264D01*
Y-230014D01*
X59027Y-231764D01*
X60119Y-233514D01*
X61429Y-234680D01*
X62957Y-234972D01*
X64485Y-234389D01*
X66014Y-232639D01*
G01X76745Y-234972D02*
Y-223306D01*
G01Y-225639D02*
X77837Y-224472D01*
X78929Y-223597D01*
X80457Y-223306D01*
X81548Y-223597D01*
X82859Y-224472D01*
G01X119605Y-218931D02*
X118295Y-218055D01*
X116767Y-217472D01*
X115020D01*
X113055Y-218347D01*
X111527Y-219805D01*
X110435Y-221556D01*
X109562Y-224472D01*
X109343Y-227097D01*
X109780Y-229722D01*
X110435Y-231472D01*
X111745Y-233222D01*
X113274Y-234389D01*
X114802Y-234972D01*
X116330D01*
X117859Y-234389D01*
X119169Y-233514D01*
X120261Y-232348D01*
G01X136232Y-234972D02*
Y-223306D01*
G01Y-225347D02*
X135359Y-224181D01*
X134048Y-223597D01*
X132520Y-223306D01*
X130992Y-223889D01*
X129682Y-225055D01*
X128808Y-226805D01*
X128372Y-229139D01*
X128808Y-231472D01*
X129682Y-233222D01*
X130992Y-234389D01*
X132520Y-234972D01*
X134048Y-234680D01*
X135359Y-233806D01*
X136232Y-232639D01*
G01X146745Y-234972D02*
Y-223306D01*
G01Y-225639D02*
X147837Y-224472D01*
X148929Y-223597D01*
X150457Y-223306D01*
X151548Y-223597D01*
X152859Y-224472D01*
G01X171232Y-217472D02*
Y-234972D01*
G01Y-232348D02*
X170359Y-233806D01*
X169048Y-234680D01*
X167520Y-234972D01*
X165774Y-234389D01*
X164464Y-232931D01*
X163590Y-231181D01*
X163372Y-229139D01*
X163590Y-227097D01*
X164464Y-225347D01*
X165774Y-223889D01*
X167520Y-223306D01*
X169048Y-223597D01*
X170140Y-224181D01*
X171232Y-225347D01*
G01X178252Y-240805D02*
X191352D01*
G01X197717Y-232639D02*
X199464Y-234097D01*
X201429Y-234972D01*
X203175D01*
X204922Y-234097D01*
X206232Y-232639D01*
X206887Y-230597D01*
X206450Y-228556D01*
X205359Y-226805D01*
X203394Y-225639D01*
X200774Y-225055D01*
X199245Y-223889D01*
X198590Y-221847D01*
X199027Y-219805D01*
X200119Y-218347D01*
X201647Y-217472D01*
X203175D01*
X204704Y-218055D01*
X206014Y-219514D01*
G01X215217Y-232639D02*
X216964Y-234097D01*
X218929Y-234972D01*
X220675D01*
X222422Y-234097D01*
X223732Y-232639D01*
X224387Y-230597D01*
X223950Y-228556D01*
X222859Y-226805D01*
X220894Y-225639D01*
X218274Y-225055D01*
X216745Y-223889D01*
X216090Y-221847D01*
X216527Y-219805D01*
X217619Y-218347D01*
X219147Y-217472D01*
X220675D01*
X222204Y-218055D01*
X223514Y-219514D01*
G01X250654Y-220389D02*
X251964Y-218639D01*
X253492Y-217764D01*
X255239Y-217472D01*
X257422Y-218055D01*
X258950Y-219514D01*
X259387Y-221263D01*
X259169Y-223014D01*
X258295Y-224472D01*
X253929Y-227389D01*
X251964Y-229430D01*
X250654Y-232348D01*
X250217Y-234972D01*
X259387D01*
G01X286527Y-232931D02*
X287619Y-234097D01*
X289147Y-234972D01*
X290457D01*
X291767Y-234389D01*
X292640Y-233514D01*
X293077Y-232348D01*
X292859Y-230597D01*
X291985Y-229722D01*
X288055Y-227972D01*
X287182Y-225930D01*
X287619Y-224472D01*
X288492Y-223597D01*
X289802Y-223306D01*
X291112Y-223597D01*
X292422Y-224472D01*
G01X307302Y-234972D02*
Y-217472D01*
G01X324802Y-234972D02*
X323492Y-234680D01*
X322182Y-233514D01*
X321308Y-231472D01*
X320872Y-229139D01*
X321308Y-226805D01*
X322182Y-224764D01*
X323492Y-223597D01*
X324802Y-223306D01*
X326112Y-223597D01*
X327422Y-224764D01*
X328295Y-226805D01*
X328514Y-229139D01*
X328295Y-231472D01*
X327422Y-233514D01*
X326112Y-234680D01*
X324802Y-234972D01*
G01X342302Y-217472D02*
Y-234972D01*
G01X339245Y-223306D02*
X345359D01*
G01X356527Y-232931D02*
X357619Y-234097D01*
X359147Y-234972D01*
X360457D01*
X361767Y-234389D01*
X362640Y-233514D01*
X363077Y-232348D01*
X362859Y-230597D01*
X361985Y-229722D01*
X358055Y-227972D01*
X357182Y-225930D01*
X357619Y-224472D01*
X358492Y-223597D01*
X359802Y-223306D01*
X361112Y-223597D01*
X362422Y-224472D01*
G01X109125Y-189972D02*
Y-172472D01*
X114802Y-187055D01*
X120479Y-172472D01*
Y-189972D01*
G01X132302D02*
X130992Y-189680D01*
X129682Y-188514D01*
X128808Y-186472D01*
X128372Y-184139D01*
X128808Y-181805D01*
X129682Y-179764D01*
X130992Y-178597D01*
X132302Y-178306D01*
X133612Y-178597D01*
X134922Y-179764D01*
X135795Y-181805D01*
X136014Y-184139D01*
X135795Y-186472D01*
X134922Y-188514D01*
X133612Y-189680D01*
X132302Y-189972D01*
G01X153732Y-172472D02*
Y-189972D01*
G01Y-187348D02*
X152859Y-188806D01*
X151548Y-189680D01*
X150020Y-189972D01*
X148274Y-189389D01*
X146964Y-187931D01*
X146090Y-186181D01*
X145872Y-184139D01*
X146090Y-182097D01*
X146964Y-180347D01*
X148274Y-178889D01*
X150020Y-178306D01*
X151548Y-178597D01*
X152640Y-179181D01*
X153732Y-180347D01*
G01X164027Y-182097D02*
X171014D01*
X170359Y-180055D01*
X169267Y-178889D01*
X167739Y-178306D01*
X166210Y-178597D01*
X164900Y-179472D01*
X164027Y-181514D01*
X163590Y-183264D01*
Y-185014D01*
X164027Y-186764D01*
X165119Y-188514D01*
X166429Y-189680D01*
X167957Y-189972D01*
X169485Y-189389D01*
X171014Y-187639D01*
G01X184802Y-189972D02*
Y-172472D01*
G01X418602Y-234972D02*
Y-217472D01*
X415982Y-220972D01*
G01Y-234972D02*
X421222D01*
G01X431299Y-232348D02*
X432608Y-233806D01*
X434137Y-234680D01*
X436102Y-234972D01*
X438067Y-234389D01*
X439595Y-233222D01*
X440687Y-231181D01*
X440905Y-228847D01*
X440469Y-226514D01*
X439377Y-225055D01*
X437848Y-223889D01*
X436320Y-223597D01*
X434792Y-223889D01*
X432827Y-225055D01*
X433482Y-217472D01*
X439377D01*
G01X449890Y-232931D02*
X451419Y-234389D01*
X453165Y-234972D01*
X454912Y-234389D01*
X456440Y-232639D01*
X457532Y-230014D01*
X457969Y-227389D01*
Y-224181D01*
X457532Y-221556D01*
X456440Y-219222D01*
X455130Y-218055D01*
X453602Y-217472D01*
X451855Y-218055D01*
X450545Y-219222D01*
X449672Y-220972D01*
X449235Y-223306D01*
X449672Y-225347D01*
X450764Y-227389D01*
X452074Y-228556D01*
X453602Y-228847D01*
X455348Y-228264D01*
X456659Y-226805D01*
X457969Y-224181D01*
G01X466954Y-227681D02*
X468482Y-225639D01*
X469792Y-224472D01*
X471539Y-223889D01*
X473067Y-224472D01*
X474159Y-225639D01*
X475032Y-227389D01*
X475250Y-229430D01*
X475032Y-231181D01*
X474159Y-232931D01*
X472848Y-234389D01*
X471320Y-234972D01*
X469574Y-234389D01*
X468045Y-232639D01*
X467172Y-230014D01*
X466954Y-227097D01*
X467390Y-223306D01*
X468045Y-221263D01*
X469137Y-219222D01*
X470665Y-217764D01*
X472194Y-217472D01*
X473722Y-218055D01*
X474814Y-219514D01*
G01X488602Y-234972D02*
X490130Y-234680D01*
X491877Y-233806D01*
X492969Y-232348D01*
X493405Y-230305D01*
X492969Y-228264D01*
X491659Y-226514D01*
X489694Y-225639D01*
X487510D01*
X486200Y-225055D01*
X485108Y-223597D01*
X484672Y-221556D01*
X485327Y-219514D01*
X486855Y-218055D01*
X488602Y-217472D01*
X490348Y-218055D01*
X491877Y-219514D01*
X492532Y-221556D01*
X492095Y-223597D01*
X491004Y-225055D01*
X489694Y-225639D01*
X487510D01*
X485545Y-226514D01*
X484235Y-228264D01*
X483799Y-230305D01*
X484235Y-232348D01*
X485327Y-233806D01*
X487074Y-234680D01*
X488602Y-234972D01*
G01X405485Y-189972D02*
Y-172472D01*
X410725D01*
X412472Y-173347D01*
X413782Y-175389D01*
X414219Y-177722D01*
X413782Y-180055D01*
X412690Y-181805D01*
X410725Y-182681D01*
X405485D01*
G01X432155Y-173931D02*
X430845Y-173055D01*
X429317Y-172472D01*
X427570D01*
X425605Y-173347D01*
X424077Y-174805D01*
X422985Y-176556D01*
X422112Y-179472D01*
X421893Y-182097D01*
X422330Y-184722D01*
X422985Y-186472D01*
X424295Y-188222D01*
X425824Y-189389D01*
X427352Y-189972D01*
X428880D01*
X430409Y-189389D01*
X431719Y-188514D01*
X432811Y-187348D01*
G01X446598Y-180639D02*
X447472Y-179764D01*
X448127Y-178306D01*
X448564Y-176263D01*
X448127Y-174514D01*
X447254Y-173347D01*
X445725Y-172472D01*
X439830D01*
Y-189972D01*
X447035D01*
X448564Y-188806D01*
X449437Y-187055D01*
X449874Y-185014D01*
X449437Y-182972D01*
X448127Y-181222D01*
X446598Y-180639D01*
X439830D01*
G01X455802Y-195805D02*
X468902D01*
G01X474830Y-189972D02*
Y-172472D01*
X484874Y-189972D01*
Y-172472D01*
G01X497352Y-189972D02*
X495605Y-189680D01*
X494077Y-188514D01*
X492767Y-186764D01*
X491893Y-184722D01*
X491457Y-182389D01*
Y-180055D01*
X491893Y-177722D01*
X492767Y-175680D01*
X494077Y-173931D01*
X495605Y-172764D01*
X497352Y-172472D01*
X499098Y-172764D01*
X500627Y-173931D01*
X501937Y-175680D01*
X502811Y-177722D01*
X503247Y-180055D01*
Y-182389D01*
X502811Y-184722D01*
X501937Y-186764D01*
X500627Y-188514D01*
X499098Y-189680D01*
X497352Y-189972D01*
G01X571152Y-234972D02*
Y-217472D01*
X568532Y-220972D01*
G01Y-234972D02*
X573772D01*
G01X583193D02*
X588652Y-217472D01*
X594111Y-234972D01*
G01X592145Y-228847D02*
X585158D01*
G01X548193Y-172472D02*
X553652Y-189972D01*
X559111Y-172472D01*
G01X575519Y-189972D02*
X566785D01*
Y-172472D01*
X575519D01*
G01X572025Y-180930D02*
X566785D01*
G01X584285Y-189972D02*
Y-172472D01*
X589744D01*
X591490Y-173347D01*
X592582Y-174514D01*
X593019Y-176847D01*
X592582Y-179181D01*
X591272Y-180639D01*
X589744Y-181514D01*
X584285D01*
G01X589744D02*
X593019Y-189972D01*
G01X606152Y-190555D02*
X605715Y-190264D01*
Y-189680D01*
X606152Y-189389D01*
X606589Y-189680D01*
Y-190264D01*
X606152Y-190555D01*
G01X754356Y-225639D02*
X753482Y-224764D01*
X752827Y-223306D01*
X752390Y-221263D01*
X752827Y-219514D01*
X753700Y-218347D01*
X755229Y-217472D01*
X761124D01*
Y-234972D01*
X753919D01*
X752390Y-233806D01*
X751517Y-232055D01*
X751080Y-230014D01*
X751517Y-227972D01*
X752827Y-226222D01*
X754356Y-225639D01*
X761124D01*
G01X744279Y-234972D02*
Y-217472D01*
X738602Y-232055D01*
X732925Y-217472D01*
Y-234972D01*
G01X726561D02*
X721102Y-217472D01*
X715643Y-234972D01*
G01X717609Y-228847D02*
X724596D01*
G01X708187Y-232639D02*
X706440Y-234097D01*
X704475Y-234972D01*
X702729D01*
X700982Y-234097D01*
X699672Y-232639D01*
X699017Y-230597D01*
X699454Y-228556D01*
X700545Y-226805D01*
X702510Y-225639D01*
X705130Y-225055D01*
X706659Y-223889D01*
X707314Y-221847D01*
X706877Y-219805D01*
X705785Y-218347D01*
X704257Y-217472D01*
X702729D01*
X701200Y-218055D01*
X699890Y-219514D01*
G01X690905Y-234972D02*
Y-217472D01*
G01X682609D02*
X690905Y-228264D01*
G01X681299Y-234972D02*
X687194Y-223306D01*
G01X681735Y-172472D02*
Y-189972D01*
X690469D01*
G01X707532D02*
Y-178306D01*
G01Y-180347D02*
X706659Y-179181D01*
X705348Y-178597D01*
X703820Y-178306D01*
X702292Y-178889D01*
X700982Y-180055D01*
X700108Y-181805D01*
X699672Y-184139D01*
X700108Y-186472D01*
X700982Y-188222D01*
X702292Y-189389D01*
X703820Y-189972D01*
X705348Y-189680D01*
X706659Y-188806D01*
X707532Y-187639D01*
G01X716517Y-195222D02*
X717827Y-195805D01*
X719574Y-195222D01*
X720665Y-194056D01*
X721539Y-192597D01*
X722848Y-187931D01*
X725687Y-178306D01*
G01X718700D02*
X722848Y-187931D01*
G01X735327Y-182097D02*
X742314D01*
X741659Y-180055D01*
X740567Y-178889D01*
X739039Y-178306D01*
X737510Y-178597D01*
X736200Y-179472D01*
X735327Y-181514D01*
X734890Y-183264D01*
Y-185014D01*
X735327Y-186764D01*
X736419Y-188514D01*
X737729Y-189680D01*
X739257Y-189972D01*
X740785Y-189389D01*
X742314Y-187639D01*
G01X753045Y-189972D02*
Y-178306D01*
G01Y-180639D02*
X754137Y-179472D01*
X755229Y-178597D01*
X756757Y-178306D01*
X757848Y-178597D01*
X759159Y-179472D01*
G01X824705Y-218931D02*
X823395Y-218055D01*
X821867Y-217472D01*
X820120D01*
X818155Y-218347D01*
X816627Y-219805D01*
X815535Y-221556D01*
X814662Y-224472D01*
X814443Y-227097D01*
X814880Y-229722D01*
X815535Y-231472D01*
X816845Y-233222D01*
X818374Y-234389D01*
X819902Y-234972D01*
X821430D01*
X822959Y-234389D01*
X824269Y-233514D01*
X825361Y-232348D01*
G01X837402Y-234972D02*
X835655Y-234680D01*
X834127Y-233514D01*
X832817Y-231764D01*
X831943Y-229722D01*
X831507Y-227389D01*
Y-225055D01*
X831943Y-222722D01*
X832817Y-220680D01*
X834127Y-218931D01*
X835655Y-217764D01*
X837402Y-217472D01*
X839148Y-217764D01*
X840677Y-218931D01*
X841987Y-220680D01*
X842861Y-222722D01*
X843297Y-225055D01*
Y-227389D01*
X842861Y-229722D01*
X841987Y-231764D01*
X840677Y-233514D01*
X839148Y-234680D01*
X837402Y-234972D01*
G01X849880D02*
Y-217472D01*
X859924Y-234972D01*
Y-217472D01*
G01X867380Y-234972D02*
Y-217472D01*
X877424Y-234972D01*
Y-217472D01*
G01X887282D02*
X892522D01*
G01X889902D02*
Y-234972D01*
G01X887282D02*
X892522D01*
G01X911769D02*
X903035D01*
Y-217472D01*
X911769D01*
G01X908275Y-225930D02*
X903035D01*
G01X937817Y-234972D02*
X946987Y-217472D01*
G01X937817D02*
X946987Y-234972D01*
G01X955317D02*
Y-217472D01*
G01X964487D02*
Y-234972D01*
G01Y-226222D02*
X955317D01*
G01X823849Y-189972D02*
Y-172472D01*
X828215D01*
X829962Y-173347D01*
X831272Y-174514D01*
X832364Y-176263D01*
X833237Y-178306D01*
X833455Y-181222D01*
X833237Y-184139D01*
X832364Y-186181D01*
X831272Y-187931D01*
X829962Y-189097D01*
X828215Y-189972D01*
X823849D01*
G01X842877Y-182097D02*
X849864D01*
X849209Y-180055D01*
X848117Y-178889D01*
X846589Y-178306D01*
X845060Y-178597D01*
X843750Y-179472D01*
X842877Y-181514D01*
X842440Y-183264D01*
Y-185014D01*
X842877Y-186764D01*
X843969Y-188514D01*
X845279Y-189680D01*
X846807Y-189972D01*
X848335Y-189389D01*
X849864Y-187639D01*
G01X860377Y-187931D02*
X861469Y-189097D01*
X862997Y-189972D01*
X864307D01*
X865617Y-189389D01*
X866490Y-188514D01*
X866927Y-187348D01*
X866709Y-185597D01*
X865835Y-184722D01*
X861905Y-182972D01*
X861032Y-180930D01*
X861469Y-179472D01*
X862342Y-178597D01*
X863652Y-178306D01*
X864962Y-178597D01*
X866272Y-179472D01*
G01X881152Y-178306D02*
Y-189972D01*
G01Y-173639D02*
X880715Y-173347D01*
Y-172764D01*
X881152Y-172472D01*
X881589Y-172764D01*
Y-173347D01*
X881152Y-173639D01*
G01X895595Y-194347D02*
X897124Y-195514D01*
X898870Y-195805D01*
X900398Y-195514D01*
X901709Y-194056D01*
X902582Y-192014D01*
Y-178306D01*
G01Y-180639D02*
X901709Y-179472D01*
X900398Y-178597D01*
X898870Y-178306D01*
X897124Y-178889D01*
X896032Y-180055D01*
X895158Y-182097D01*
X894722Y-184139D01*
X894940Y-185889D01*
X895814Y-187931D01*
X897124Y-189389D01*
X898870Y-189972D01*
X900180Y-189680D01*
X901709Y-188514D01*
X902582Y-187348D01*
G01X912440Y-189972D02*
Y-178306D01*
G01Y-181222D02*
X913314Y-179764D01*
X914624Y-178597D01*
X916370Y-178306D01*
X917898Y-178597D01*
X919209Y-179764D01*
X919864Y-181805D01*
Y-189972D01*
G01X930377Y-182097D02*
X937364D01*
X936709Y-180055D01*
X935617Y-178889D01*
X934089Y-178306D01*
X932560Y-178597D01*
X931250Y-179472D01*
X930377Y-181514D01*
X929940Y-183264D01*
Y-185014D01*
X930377Y-186764D01*
X931469Y-188514D01*
X932779Y-189680D01*
X934307Y-189972D01*
X935835Y-189389D01*
X937364Y-187639D01*
G01X948095Y-189972D02*
Y-178306D01*
G01Y-180639D02*
X949187Y-179472D01*
X950279Y-178597D01*
X951807Y-178306D01*
X952898Y-178597D01*
X954209Y-179472D01*
G01X994852Y-217472D02*
X993105Y-218055D01*
X991795Y-219514D01*
X990922Y-221263D01*
X990267Y-223597D01*
X990049Y-226222D01*
X990267Y-228847D01*
X990922Y-231181D01*
X991795Y-232931D01*
X993105Y-234389D01*
X994852Y-234972D01*
X996598Y-234389D01*
X997909Y-232931D01*
X998782Y-231181D01*
X999437Y-228847D01*
X999655Y-226222D01*
X999437Y-223597D01*
X998782Y-221263D01*
X997909Y-219514D01*
X996598Y-218055D01*
X994852Y-217472D01*
G01X1012352Y-234972D02*
X1013880Y-234680D01*
X1015627Y-233806D01*
X1016719Y-232348D01*
X1017155Y-230305D01*
X1016719Y-228264D01*
X1015409Y-226514D01*
X1013444Y-225639D01*
X1011260D01*
X1009950Y-225055D01*
X1008858Y-223597D01*
X1008422Y-221556D01*
X1009077Y-219514D01*
X1010605Y-218055D01*
X1012352Y-217472D01*
X1014098Y-218055D01*
X1015627Y-219514D01*
X1016282Y-221556D01*
X1015845Y-223597D01*
X1014754Y-225055D01*
X1013444Y-225639D01*
X1011260D01*
X1009295Y-226514D01*
X1007985Y-228264D01*
X1007549Y-230305D01*
X1007985Y-232348D01*
X1009077Y-233806D01*
X1010824Y-234680D01*
X1012352Y-234972D01*
G01X1025922Y-235555D02*
X1033782Y-217472D01*
G01X1043204Y-220389D02*
X1044514Y-218639D01*
X1046042Y-217764D01*
X1047789Y-217472D01*
X1049972Y-218055D01*
X1051500Y-219514D01*
X1051937Y-221263D01*
X1051719Y-223014D01*
X1050845Y-224472D01*
X1046479Y-227389D01*
X1044514Y-229430D01*
X1043204Y-232348D01*
X1042767Y-234972D01*
X1051937D01*
G01X1060049Y-232348D02*
X1061358Y-233806D01*
X1062887Y-234680D01*
X1064852Y-234972D01*
X1066817Y-234389D01*
X1068345Y-233222D01*
X1069437Y-231181D01*
X1069655Y-228847D01*
X1069219Y-226514D01*
X1068127Y-225055D01*
X1066598Y-223889D01*
X1065070Y-223597D01*
X1063542Y-223889D01*
X1061577Y-225055D01*
X1062232Y-217472D01*
X1068127D01*
G01X1078422Y-235555D02*
X1086282Y-217472D01*
G01X1095704Y-220389D02*
X1097014Y-218639D01*
X1098542Y-217764D01*
X1100289Y-217472D01*
X1102472Y-218055D01*
X1104000Y-219514D01*
X1104437Y-221263D01*
X1104219Y-223014D01*
X1103345Y-224472D01*
X1098979Y-227389D01*
X1097014Y-229430D01*
X1095704Y-232348D01*
X1095267Y-234972D01*
X1104437D01*
G01X1117352Y-217472D02*
X1115605Y-218055D01*
X1114295Y-219514D01*
X1113422Y-221263D01*
X1112767Y-223597D01*
X1112549Y-226222D01*
X1112767Y-228847D01*
X1113422Y-231181D01*
X1114295Y-232931D01*
X1115605Y-234389D01*
X1117352Y-234972D01*
X1119098Y-234389D01*
X1120409Y-232931D01*
X1121282Y-231181D01*
X1121937Y-228847D01*
X1122155Y-226222D01*
X1121937Y-223597D01*
X1121282Y-221263D01*
X1120409Y-219514D01*
X1119098Y-218055D01*
X1117352Y-217472D01*
G01X1134852Y-234972D02*
Y-217472D01*
X1132232Y-220972D01*
G01Y-234972D02*
X1137472D01*
G01X1148204Y-227681D02*
X1149732Y-225639D01*
X1151042Y-224472D01*
X1152789Y-223889D01*
X1154317Y-224472D01*
X1155409Y-225639D01*
X1156282Y-227389D01*
X1156500Y-229430D01*
X1156282Y-231181D01*
X1155409Y-232931D01*
X1154098Y-234389D01*
X1152570Y-234972D01*
X1150824Y-234389D01*
X1149295Y-232639D01*
X1148422Y-230014D01*
X1148204Y-227097D01*
X1148640Y-223306D01*
X1149295Y-221263D01*
X1150387Y-219222D01*
X1151915Y-217764D01*
X1153444Y-217472D01*
X1154972Y-218055D01*
X1156064Y-219514D01*
G01X1042549Y-189972D02*
Y-172472D01*
X1046915D01*
X1048662Y-173347D01*
X1049972Y-174514D01*
X1051064Y-176263D01*
X1051937Y-178306D01*
X1052155Y-181222D01*
X1051937Y-184139D01*
X1051064Y-186181D01*
X1049972Y-187931D01*
X1048662Y-189097D01*
X1046915Y-189972D01*
X1042549D01*
G01X1068782D02*
Y-178306D01*
G01Y-180347D02*
X1067909Y-179181D01*
X1066598Y-178597D01*
X1065070Y-178306D01*
X1063542Y-178889D01*
X1062232Y-180055D01*
X1061358Y-181805D01*
X1060922Y-184139D01*
X1061358Y-186472D01*
X1062232Y-188222D01*
X1063542Y-189389D01*
X1065070Y-189972D01*
X1066598Y-189680D01*
X1067909Y-188806D01*
X1068782Y-187639D01*
G01X1082352Y-172472D02*
Y-189972D01*
G01X1079295Y-178306D02*
X1085409D01*
G01X1096577Y-182097D02*
X1103564D01*
X1102909Y-180055D01*
X1101817Y-178889D01*
X1100289Y-178306D01*
X1098760Y-178597D01*
X1097450Y-179472D01*
X1096577Y-181514D01*
X1096140Y-183264D01*
Y-185014D01*
X1096577Y-186764D01*
X1097669Y-188514D01*
X1098979Y-189680D01*
X1100507Y-189972D01*
X1102035Y-189389D01*
X1103564Y-187639D01*
G54D39*
X30900Y62550D03*
M02*
